# BASEBOARD_FAB2 (Tioga Pass) — schematic netlist excerpt (pin names and nets, part order shuffled) for the footprints in the layout excerpt that follows; sources: Cadence DE-HDL packaged netlist, KiCad conversion of Wiwynn_Tioga_Pass_MB.brd

J4G1  SCONN288_H44441004  SCONN  pkg PIP  page 43
  \12v\(1)  = P12V_NVDIMM_ABC
  VSS(93)  = GND
  DQ(4)  = M_A_DQ<5>
  VSS(92)  = GND
  DQ(0)  = M_A_DQ<1>
  VSS(91)  = GND
  DQS9P  = M_A_DQS_DP<9>
  DQS9N  = M_A_DQS_DN<9>
  VSS(90)  = GND
  DQ(6)  = M_A_DQ<7>
  VSS(89)  = GND
  DQ(2)  = M_A_DQ<3>
  VSS(88)  = GND
  DQ(12)  = M_A_DQ<13>
  VSS(87)  = GND
  DQ(8)  = M_A_DQ<9>
  VSS(86)  = GND
  DQS10P  = M_A_DQS_DP<10>
  DQS10N  = M_A_DQS_DN<10>
  VSS(85)  = GND
  DQ(14)  = M_A_DQ<15>
  VSS(84)  = GND
  DQ(10)  = M_A_DQ<11>
  VSS(83)  = GND
  DQ(20)  = M_A_DQ<21>
  VSS(82)  = GND
  DQ(16)  = M_A_DQ<17>
  VSS(81)  = GND
  DQS11P  = M_A_DQS_DP<11>
  DQS11N  = M_A_DQS_DN<11>
  VSS(80)  = GND
  DQ(22)  = M_A_DQ<23>
  VSS(79)  = GND
  DQ(18)  = M_A_DQ<19>
  VSS(78)  = GND
  DQ(28)  = M_A_DQ<29>
  VSS(77)  = GND
  DQ(24)  = M_A_DQ<25>
  VSS(76)  = GND
  DQS12P  = M_A_DQS_DP<12>
  DQS12N  = M_A_DQS_DN<12>
  VSS(75)  = GND
  DQ(30)  = M_A_DQ<31>
  VSS(74)  = GND
  DQ(26)  = M_A_DQ<27>
  VSS(73)  = GND
  CB(4)  = M_A_ECC<5>
  VSS(72)  = GND
  CB(0)  = M_A_ECC<1>
  VSS(71)  = GND
  DQS17P  = M_A_DQS_DP<17>
  DQS17N  = M_A_DQS_DN<17>
  VSS(70)  = GND
  CB(6)  = M_A_ECC<7>
  VSS(69)  = GND
  CB(2)  = M_A_ECC<3>
  VSS(68)  = GND
  RESET_N  = M_ABC_RST_N
  VDD(25)  = PVDDQ_ABC
  CKE(0)  = M_A_CKE<0>
  VDD(24)  = PVDDQ_ABC
  ACT_N  = M_A_ACT_N
  BG(0)  = M_A_BG<0>
  VDD(23)  = PVDDQ_ABC
  A12  = M_A_MA<12>
  A9  = M_A_MA<9>
  VDD(22)  = PVDDQ_ABC
  A8  = M_A_MA<8>
  A6  = M_A_MA<6>
  VDD(21)  = PVDDQ_ABC
  A3  = M_A_MA<3>
  A1  = M_A_MA<1>
  VDD(20)  = PVDDQ_ABC
  CK0P  = M_A_CLK_DP<0>
  CK0N  = M_A_CLK_DN<0>
  VDD(19)  = PVDDQ_ABC
  VTT(1)  = PVTT_ABC
  EVENT_N  = FM_DIMM_EVENT_COD_N
  A0  = M_A_MA<0>
  VDD(18)  = PVDDQ_ABC
  BA(0)  = M_A_BA<0>
  A16_RAS_N  = M_A_MA<16>
  VDD(17)  = PVDDQ_ABC
  S0_N  = M_A_CS_N<0>
  VDD(16)  = PVDDQ_ABC
  A15_CAS_N  = M_A_MA<15>
  ODT(0)  = M_A_ODT<0>
  VDD(15)  = PVDDQ_ABC
  S1_N  = M_A_CS_N<1>
  VDD(14)  = PVDDQ_ABC
  ODT(1)  = M_A_ODT<1>
  VDD(13)  = PVDDQ_ABC
  S2_N_C(0)  = M_A_CS_N<2>
  VSS(67)  = GND
  DQ(36)  = M_A_DQ<37>
  VSS(66)  = GND
  DQ(32)  = M_A_DQ<33>
  VSS(65)  = GND
  DQS13P  = M_A_DQS_DP<13>
  DQS13N  = M_A_DQS_DN<13>
  VSS(64)  = GND
  DQ(38)  = M_A_DQ<39>
  VSS(63)  = GND
  DQ(34)  = M_A_DQ<35>
  VSS(62)  = GND
  DQ(44)  = M_A_DQ<45>
  VSS(61)  = GND
  DQ(40)  = M_A_DQ<41>
  VSS(60)  = GND
  DQS14P  = M_A_DQS_DP<14>
  DQS14N  = M_A_DQS_DN<14>
  VSS(59)  = GND
  DQ(46)  = M_A_DQ<47>
  VSS(58)  = GND
  DQ(42)  = M_A_DQ<43>
  VSS(57)  = GND
  DQ(52)  = M_A_DQ<53>
  VSS(56)  = GND
  DQ(48)  = M_A_DQ<49>
  VSS(55)  = GND
  DQS15P  = M_A_DQS_DP<15>
  DQS15N  = M_A_DQS_DN<15>
  VSS(54)  = GND
  DQ(54)  = M_A_DQ<55>
  VSS(53)  = GND
  DQ(50)  = M_A_DQ<51>
  VSS(52)  = GND
  DQ(60)  = M_A_DQ<61>
  VSS(51)  = GND
  DQ(56)  = M_A_DQ<57>
  VSS(50)  = GND
  DQS16P  = M_A_DQS_DP<16>
  DQS16N  = M_A_DQS_DN<16>
  VSS(49)  = GND
  DQ(62)  = M_A_DQ<63>
  VSS(48)  = GND
  DQ(58)  = M_A_DQ<59>
  VSS(47)  = GND
  SA(0)  = GND
  SA(1)  = GND
  SCL  = SMB_DDR_ABC_VPP_SCL
  VPP(4)  = PVPP_ABC
  VPP(3)  = PVPP_ABC
  RFU(2)  = TP_CH_A_DIMM_A0_RFU_2
  \12v\(0)  = P12V_NVDIMM_ABC
  VREFCA  = M_A_VREF
  VSS(46)  = GND
  DQ(5)  = M_A_DQ<4>
  VSS(45)  = GND
  DQ(1)  = M_A_DQ<0>
  VSS(44)  = GND
  DQS0N  = M_A_DQS_DN<0>
  DQS0P  = M_A_DQS_DP<0>
  VSS(43)  = GND
  DQ(7)  = M_A_DQ<6>
  VSS(42)  = GND
  DQ(3)  = M_A_DQ<2>
  VSS(41)  = GND
  DQ(13)  = M_A_DQ<12>
  VSS(40)  = GND
  DQ(9)  = M_A_DQ<8>
  VSS(39)  = GND
  DQS1N  = M_A_DQS_DN<1>
  DQS1P  = M_A_DQS_DP<1>
  VSS(38)  = GND
  DQ(15)  = M_A_DQ<14>
  VSS(37)  = GND
  DQ(11)  = M_A_DQ<10>
  VSS(36)  = GND
  DQ(21)  = M_A_DQ<20>
  VSS(35)  = GND
  DQ(17)  = M_A_DQ<16>
  VSS(34)  = GND
  DQS2N  = M_A_DQS_DN<2>
  DQS2P  = M_A_DQS_DP<2>
  VSS(33)  = GND
  DQ(23)  = M_A_DQ<22>
  VSS(32)  = GND
  DQ(19)  = M_A_DQ<18>
  VSS(31)  = GND
  DQ(29)  = M_A_DQ<28>
  VSS(30)  = GND
  DQ(25)  = M_A_DQ<24>
  VSS(29)  = GND
  DQS3N  = M_A_DQS_DN<3>
  DQS3P  = M_A_DQS_DP<3>
  VSS(28)  = GND
  DQ(31)  = M_A_DQ<30>
  VSS(27)  = GND
  DQ(27)  = M_A_DQ<26>
  VSS(26)  = GND
  CB(5)  = M_A_ECC<4>
  VSS(25)  = GND
  CB(1)  = M_A_ECC<0>
  VSS(24)  = GND
  DQS8N  = M_A_DQS_DN<8>
  DQS8P  = M_A_DQS_DP<8>
  VSS(23)  = GND
  CB(7)  = M_A_ECC<6>
  VSS(22)  = GND
  CB(3)  = M_A_ECC<2>
  VSS(21)  = GND
  CKE(1)  = M_A_CKE<1>
  VDD(12)  = PVDDQ_ABC
  RFU(0)  = TP_CH_A_DIMM_A0_RFU_0
  VDD(11)  = PVDDQ_ABC
  BG(1)  = M_A_BG<1>
  ALERT_N  = M_A_ALERT_N
  VDD(10)  = PVDDQ_ABC
  A11  = M_A_MA<11>
  A7  = M_A_MA<7>
  VDD(9)  = PVDDQ_ABC
  A5  = M_A_MA<5>
  A4  = M_A_MA<4>
  VDD(8)  = PVDDQ_ABC
  A2  = M_A_MA<2>
  VDD(7)  = PVDDQ_ABC
  CK1P  = M_A_CLK_DP<1>
  CK1N  = M_A_CLK_DN<1>
  VDD(6)  = PVDDQ_ABC
  VTT(0)  = PVTT_ABC
  PAR  = M_A_PAR
  VDD(5)  = PVDDQ_ABC
  BA(1)  = M_A_BA<1>
  A10  = M_A_MA<10>
  VDD(4)  = PVDDQ_ABC
  RFU(1)  = TP_CH_A_DIMM_A0_RFU_1
  A14_WE_N  = M_A_MA<14>
  VDD(3)  = PVDDQ_ABC
  SAVE_N_NC  = FM_ADR_COMPLETE_ABC_N
  VDD(2)  = PVDDQ_ABC
  A13  = M_A_MA<13>
  VDD(1)  = PVDDQ_ABC
  A17  = M_A_MA<17>
  C(2)  = M_A_C<2>
  VDD(0)  = PVDDQ_ABC
  S3_N_C(1)  = M_A_CS_N<3>
  SA(2)  = GND
  VSS(20)  = GND
  DQ(37)  = M_A_DQ<36>
  VSS(19)  = GND
  DQ(33)  = M_A_DQ<32>
  VSS(18)  = GND
  DQS4N  = M_A_DQS_DN<4>
  DQS4P  = M_A_DQS_DP<4>
  VSS(17)  = GND
  DQ(39)  = M_A_DQ<38>
  VSS(16)  = GND
  DQ(35)  = M_A_DQ<34>
  VSS(15)  = GND
  DQ(45)  = M_A_DQ<44>
  VSS(14)  = GND
  DQ(41)  = M_A_DQ<40>
  VSS(13)  = GND
  DQS5N  = M_A_DQS_DN<5>
  DQS5P  = M_A_DQS_DP<5>
  VSS(12)  = GND
  DQ(47)  = M_A_DQ<46>
  VSS(11)  = GND
  DQ(43)  = M_A_DQ<42>
  VSS(10)  = GND
  DQ(53)  = M_A_DQ<52>
  VSS(9)  = GND
  DQ(49)  = M_A_DQ<48>
  VSS(8)  = GND
  DQS6N  = M_A_DQS_DN<6>
  DQS6P  = M_A_DQS_DP<6>
  VSS(7)  = GND
  DQ(55)  = M_A_DQ<54>
  VSS(6)  = GND
  DQ(51)  = M_A_DQ<50>
  VSS(5)  = GND
  DQ(61)  = M_A_DQ<60>
  VSS(4)  = GND
  DQ(57)  = M_A_DQ<56>
  VSS(3)  = GND
  DQS7N  = M_A_DQS_DN<7>
  DQS7P  = M_A_DQS_DP<7>
  VSS(2)  = GND
  DQ(63)  = M_A_DQ<62>
  VSS(1)  = GND
  DQ(59)  = M_A_DQ<58>
  VSS(0)  = GND
  VDDSPD  = PVPP_ABC
  SDA  = SMB_DDR_ABC_VPP_SDA
  VPP(1)  = PVPP_ABC
  VPP(0)  = PVPP_ABC
  VPP(2)  = PVPP_ABC

(kicad_pcb
	(version 20260206)
	(generator "pcbnew")
	(generator_version "10.0")
	(general
		(thickness 1.6)
		(legacy_teardrops no)
	)
	(paper "A4")
	(title_block
		(title "Wiwynn_Tioga_Pass_MB.brd")
		(comment 1 "Tioga Pass / footprint 2167 of 4770 (J4G1), pads 102-152 of 291")
	)
	(layers
		(0 "F.Cu" signal "TOP")
		(4 "In1.Cu" signal "L2GND")
		(6 "In2.Cu" signal "L3")
		(8 "In3.Cu" signal "L4GND")
		(10 "In4.Cu" signal "L5")
		(12 "In5.Cu" signal "L6GND")
		(14 "In6.Cu" signal "L7VCC")
		(16 "In7.Cu" signal "L8VCC")
		(18 "In8.Cu" signal "L9GND")
		(20 "In9.Cu" signal "L10")
		(22 "In10.Cu" signal "L11GND")
		(24 "In11.Cu" signal "L12")
		(26 "In12.Cu" signal "L13GND")
		(2 "B.Cu" signal "BOTTOM")
		(9 "F.Adhes" user "F.Adhesive")
		(11 "B.Adhes" user "B.Adhesive")
		(13 "F.Paste" user "Package Geometry/Pastemask Top")
		(15 "B.Paste" user "Package Geometry/Pastemask Bottom")
		(5 "F.SilkS" user "Ref Des/Silkscreen Top")
		(7 "B.SilkS" user "Ref Des/Silkscreen Bottom")
		(1 "F.Mask" user "Board Geometry/Soldermask Top")
		(3 "B.Mask" user "Board Geometry/Soldermask Bottom")
		(17 "Dwgs.User" user "User.Drawings")
		(19 "Cmts.User" user "User.Comments")
		(21 "Eco1.User" user "User.Eco1")
		(23 "Eco2.User" user "User.Eco2")
		(25 "Edge.Cuts" user "Board Geometry/Outline")
		(27 "Margin" user)
		(31 "F.CrtYd" user "Package Geometry/Place Bound Top")
		(29 "B.CrtYd" user "Package Geometry/Place Bound Bottom")
		(35 "F.Fab" user "Ref Des/Assembly Top")
		(33 "B.Fab" user "Ref Des/Assembly Bottom")
	)
	(footprint ""
		(layer "F.Cu")
		(at 194.700398 -15.423642 90)
		(property "Reference" "J4G1"
			(at 9.060688 37.32911 0)
			(unlocked yes)
			(layer "F.SilkS")
			(effects
				(font
					(size 0.7874 0.5842)
					(thickness 0.1524)
				)
				(justify left)
			)
		)
		(property "Value" ""
			(at 0 0 90)
			(layer "F.Fab")
			(effects
				(font
					(size 1.27 1.27)
				)
			)
		)
		(duplicate_pad_numbers_are_jumpers no)
		(pad "99" smd rect
			(at 0 88.399874 90)
			(size 1.8034 0.508)
			(layers "F.Cu" "F.Mask" "F.Paste")
			(net "M_A_DQS_DP<13>")
		)
		(pad "100" smd rect
			(at 0 89.250012 90)
			(size 1.8034 0.508)
			(layers "F.Cu" "F.Mask" "F.Paste")
			(net "M_A_DQS_DN<13>")
		)
		(pad "101" smd rect
			(at 0 90.099896 90)
			(size 1.8034 0.508)
			(layers "F.Cu" "F.Mask" "F.Paste")
			(net "GND")
		)
		(pad "102" smd rect
			(at 0 90.950034 90)
			(size 1.8034 0.508)
			(layers "F.Cu" "F.Mask" "F.Paste")
			(net "M_A_DQ<39>")
		)
		(pad "103" smd rect
			(at 0 91.799918 90)
			(size 1.8034 0.508)
			(layers "F.Cu" "F.Mask" "F.Paste")
			(net "GND")
		)
		(pad "104" smd rect
			(at 0 92.650056 90)
			(size 1.8034 0.508)
			(layers "F.Cu" "F.Mask" "F.Paste")
			(net "M_A_DQ<35>")
		)
		(pad "105" smd rect
			(at 0 93.49994 90)
			(size 1.8034 0.508)
			(layers "F.Cu" "F.Mask" "F.Paste")
			(net "GND")
		)
		(pad "106" smd rect
			(at 0 94.350078 90)
			(size 1.8034 0.508)
			(layers "F.Cu" "F.Mask" "F.Paste")
			(net "M_A_DQ<45>")
		)
		(pad "107" smd rect
			(at 0 95.199962 90)
			(size 1.8034 0.508)
			(layers "F.Cu" "F.Mask" "F.Paste")
			(net "GND")
		)
		(pad "108" smd rect
			(at 0 96.0501 90)
			(size 1.8034 0.508)
			(layers "F.Cu" "F.Mask" "F.Paste")
			(net "M_A_DQ<41>")
		)
		(pad "109" smd rect
			(at 0 96.899984 90)
			(size 1.8034 0.508)
			(layers "F.Cu" "F.Mask" "F.Paste")
			(net "GND")
		)
		(pad "110" smd rect
			(at 0 97.750122 90)
			(size 1.8034 0.508)
			(layers "F.Cu" "F.Mask" "F.Paste")
			(net "M_A_DQS_DP<14>")
		)
		(pad "111" smd rect
			(at 0 98.600006 90)
			(size 1.8034 0.508)
			(layers "F.Cu" "F.Mask" "F.Paste")
			(net "M_A_DQS_DN<14>")
		)
		(pad "112" smd rect
			(at 0 99.44989 90)
			(size 1.8034 0.508)
			(layers "F.Cu" "F.Mask" "F.Paste")
			(net "GND")
		)
		(pad "113" smd rect
			(at 0 100.300028 90)
			(size 1.8034 0.508)
			(layers "F.Cu" "F.Mask" "F.Paste")
			(net "M_A_DQ<47>")
		)
		(pad "114" smd rect
			(at 0 101.149912 90)
			(size 1.8034 0.508)
			(layers "F.Cu" "F.Mask" "F.Paste")
			(net "GND")
		)
		(pad "115" smd rect
			(at 0 102.00005 90)
			(size 1.8034 0.508)
			(layers "F.Cu" "F.Mask" "F.Paste")
			(net "M_A_DQ<43>")
		)
		(pad "116" smd rect
			(at 0 102.849934 90)
			(size 1.8034 0.508)
			(layers "F.Cu" "F.Mask" "F.Paste")
			(net "GND")
		)
		(pad "117" smd rect
			(at 0 103.700072 90)
			(size 1.8034 0.508)
			(layers "F.Cu" "F.Mask" "F.Paste")
			(net "M_A_DQ<53>")
		)
		(pad "118" smd rect
			(at 0 104.549956 90)
			(size 1.8034 0.508)
			(layers "F.Cu" "F.Mask" "F.Paste")
			(net "GND")
		)
		(pad "119" smd rect
			(at 0 105.400094 90)
			(size 1.8034 0.508)
			(layers "F.Cu" "F.Mask" "F.Paste")
			(net "M_A_DQ<49>")
		)
		(pad "120" smd rect
			(at 0 106.249978 90)
			(size 1.8034 0.508)
			(layers "F.Cu" "F.Mask" "F.Paste")
			(net "GND")
		)
		(pad "121" smd rect
			(at 0 107.100116 90)
			(size 1.8034 0.508)
			(layers "F.Cu" "F.Mask" "F.Paste")
			(net "M_A_DQS_DP<15>")
		)
		(pad "122" smd rect
			(at 0 107.95 90)
			(size 1.8034 0.508)
			(layers "F.Cu" "F.Mask" "F.Paste")
			(net "M_A_DQS_DN<15>")
		)
		(pad "123" smd rect
			(at 0 108.799884 90)
			(size 1.8034 0.508)
			(layers "F.Cu" "F.Mask" "F.Paste")
			(net "GND")
		)
		(pad "124" smd rect
			(at 0 109.650022 90)
			(size 1.8034 0.508)
			(layers "F.Cu" "F.Mask" "F.Paste")
			(net "M_A_DQ<55>")
		)
		(pad "125" smd rect
			(at 0 110.499906 90)
			(size 1.8034 0.508)
			(layers "F.Cu" "F.Mask" "F.Paste")
			(net "GND")
		)
		(pad "126" smd rect
			(at 0 111.350044 90)
			(size 1.8034 0.508)
			(layers "F.Cu" "F.Mask" "F.Paste")
			(net "M_A_DQ<51>")
		)
		(pad "127" smd rect
			(at 0 112.199928 90)
			(size 1.8034 0.508)
			(layers "F.Cu" "F.Mask" "F.Paste")
			(net "GND")
		)
		(pad "128" smd rect
			(at 0 113.050066 90)
			(size 1.8034 0.508)
			(layers "F.Cu" "F.Mask" "F.Paste")
			(net "M_A_DQ<61>")
		)
		(pad "129" smd rect
			(at 0 113.89995 90)
			(size 1.8034 0.508)
			(layers "F.Cu" "F.Mask" "F.Paste")
			(net "GND")
		)
		(pad "130" smd rect
			(at 0 114.750088 90)
			(size 1.8034 0.508)
			(layers "F.Cu" "F.Mask" "F.Paste")
			(net "M_A_DQ<57>")
		)
		(pad "131" smd rect
			(at 0 115.599972 90)
			(size 1.8034 0.508)
			(layers "F.Cu" "F.Mask" "F.Paste")
			(net "GND")
		)
		(pad "132" smd rect
			(at 0 116.45011 90)
			(size 1.8034 0.508)
			(layers "F.Cu" "F.Mask" "F.Paste")
			(net "M_A_DQS_DP<16>")
		)
		(pad "133" smd rect
			(at 0 117.299994 90)
			(size 1.8034 0.508)
			(layers "F.Cu" "F.Mask" "F.Paste")
			(net "M_A_DQS_DN<16>")
		)
		(pad "134" smd rect
			(at 0 118.149878 90)
			(size 1.8034 0.508)
			(layers "F.Cu" "F.Mask" "F.Paste")
			(net "GND")
		)
		(pad "135" smd rect
			(at 0 119.000016 90)
			(size 1.8034 0.508)
			(layers "F.Cu" "F.Mask" "F.Paste")
			(net "M_A_DQ<63>")
		)
		(pad "136" smd rect
			(at 0 119.8499 90)
			(size 1.8034 0.508)
			(layers "F.Cu" "F.Mask" "F.Paste")
			(net "GND")
		)
		(pad "137" smd rect
			(at 0 120.700038 90)
			(size 1.8034 0.508)
			(layers "F.Cu" "F.Mask" "F.Paste")
			(net "M_A_DQ<59>")
		)
		(pad "138" smd rect
			(at 0 121.549922 90)
			(size 1.8034 0.508)
			(layers "F.Cu" "F.Mask" "F.Paste")
			(net "GND")
		)
		(pad "139" smd rect
			(at 0 122.40006 90)
			(size 1.8034 0.508)
			(layers "F.Cu" "F.Mask" "F.Paste")
			(net "GND")
		)
		(pad "140" smd rect
			(at 0 123.249944 90)
			(size 1.8034 0.508)
			(layers "F.Cu" "F.Mask" "F.Paste")
			(net "GND")
		)
		(pad "141" smd rect
			(at 0 124.100082 90)
			(size 1.8034 0.508)
			(layers "F.Cu" "F.Mask" "F.Paste")
			(net "SMB_DDR_ABC_VPP_SCL")
		)
		(pad "142" smd rect
			(at 0 124.949966 90)
			(size 1.8034 0.508)
			(layers "F.Cu" "F.Mask" "F.Paste")
			(net "PVPP_ABC")
		)
		(pad "143" smd rect
			(at 0 125.800104 90)
			(size 1.8034 0.508)
			(layers "F.Cu" "F.Mask" "F.Paste")
			(net "PVPP_ABC")
		)
		(pad "144" smd rect
			(at 0 126.649988 90)
			(size 1.8034 0.508)
			(layers "F.Cu" "F.Mask" "F.Paste")
			(net "TP_CH_A_DIMM_A0_RFU_2")
		)
		(pad "145" smd rect
			(at 4.59994 0 90)
			(size 1.8034 0.508)
			(layers "F.Cu" "F.Mask" "F.Paste")
			(net "P12V_NVDIMM_ABC")
		)
		(pad "146" smd rect
			(at 4.59994 0.849884 90)
			(size 1.8034 0.508)
			(layers "F.Cu" "F.Mask" "F.Paste")
			(net "M_A_VREF")
		)
		(pad "147" smd rect
			(at 4.59994 1.700022 90)
			(size 1.8034 0.508)
			(layers "F.Cu" "F.Mask" "F.Paste")
			(net "GND")
		)
		(pad "148" smd rect
			(at 4.59994 2.549906 90)
			(size 1.8034 0.508)
			(layers "F.Cu" "F.Mask" "F.Paste")
			(net "M_A_DQ<4>")
		)
		(pad "149" smd rect
			(at 4.59994 3.400044 90)
			(size 1.8034 0.508)
			(layers "F.Cu" "F.Mask" "F.Paste")
			(net "GND")
		)
	)
)
